# T6G (Grand Teton) — schematic netlist excerpt (pin names and nets, part order shuffled) for the footprints in the layout excerpt that follows; sources: Cadence DE-HDL packaged netlist, KiCad conversion of 04192023_DAF0TMB3IC0_F0TG_MB_C_brd_V02_OCP.brd

C1053  Q_CAP  0.1UF 10V 10% X7S  pkg C0201  page 312 : A = P0V9_CPU0_RT3_2A ; B = GND
R365  Q_RES  4.7K 5% EMPTY  pkg 0402LF  page 160 : A = P3V3 ; B = SMB_CPU0_CPU1_APML_BUF1_SDA_R2
C213  Q_CAP  3.9P 50V 0.1P NPO  pkg C0402  page 28 : A = XTAL_CPU0_X48M_X1 ; B = GND

(kicad_pcb
	(version 20260206)
	(generator "pcbnew")
	(generator_version "10.0")
	(general
		(thickness 1.6)
		(legacy_teardrops no)
	)
	(paper "A4")
	(title_block
		(title "04192023_DAF0TMB3IC0_F0TG_MB_C_brd_V02_OCP.brd")
		(comment 1 "Grand Teton / footprints 6789-6791 of 8354")
	)
	(layers
		(0 "F.Cu" signal "TOP")
		(4 "In1.Cu" signal "GND")
		(6 "In2.Cu" signal "IN1")
		(8 "In3.Cu" signal "GND1")
		(10 "In4.Cu" signal "IN2")
		(12 "In5.Cu" signal "GND2")
		(14 "In6.Cu" signal "IN3")
		(16 "In7.Cu" signal "GND3")
		(18 "In8.Cu" signal "VCC")
		(20 "In9.Cu" signal "VCC1")
		(22 "In10.Cu" signal "GND4")
		(24 "In11.Cu" signal "IN4")
		(26 "In12.Cu" signal "GND5")
		(28 "In13.Cu" signal "IN5")
		(30 "In14.Cu" signal "GND6")
		(32 "In15.Cu" signal "IN6")
		(34 "In16.Cu" signal "GND7")
		(2 "B.Cu" signal "BOTTOM")
		(9 "F.Adhes" user "F.Adhesive")
		(11 "B.Adhes" user "B.Adhesive")
		(13 "F.Paste" user "Package Geometry/Pastemask Top")
		(15 "B.Paste" user "Package Geometry/Pastemask Bottom")
		(5 "F.SilkS" user "Ref Des/Silkscreen Top")
		(7 "B.SilkS" user "Ref Des/Silkscreen Bottom")
		(1 "F.Mask" user "Board Geometry/Soldermask Top")
		(3 "B.Mask" user "Board Geometry/Soldermask Bottom")
		(17 "Dwgs.User" user "User.Drawings")
		(19 "Cmts.User" user "User.Comments")
		(21 "Eco1.User" user "User.Eco1")
		(23 "Eco2.User" user "User.Eco2")
		(25 "Edge.Cuts" user "Board Geometry/Outline")
		(27 "Margin" user)
		(31 "F.CrtYd" user "Package Geometry/Place Bound Top")
		(29 "B.CrtYd" user "Package Geometry/Place Bound Bottom")
		(35 "F.Fab" user "Ref Des/Assembly Top")
		(33 "B.Fab" user "Ref Des/Assembly Bottom")
	)
	(footprint ""
		(layer "B.Cu")
		(at 396.052802 -314.366148)
		(property "Reference" "C213"
			(at 0 0 0)
			(layer "B.SilkS")
			(hide yes)
			(effects
				(font
					(size 1.27 1.27)
				)
				(justify mirror)
			)
		)
		(property "Value" ""
			(at 0 0 0)
			(layer "B.Fab")
			(effects
				(font
					(size 1.27 1.27)
				)
				(justify mirror)
			)
		)
		(duplicate_pad_numbers_are_jumpers no)
		(fp_line
			(start -0.7874 -0.4064)
			(end -0.7874 0.4064)
			(stroke
				(width 0.1524)
				(type default)
			)
			(layer "B.SilkS")
		)
		(fp_line
			(start -0.7874 0.4064)
			(end 0.7874 0.4064)
			(stroke
				(width 0.1524)
				(type default)
			)
			(layer "B.SilkS")
		)
		(fp_line
			(start 0.7874 -0.4064)
			(end -0.7874 -0.4064)
			(stroke
				(width 0.1524)
				(type default)
			)
			(layer "B.SilkS")
		)
		(fp_line
			(start 0.7874 0.4064)
			(end 0.7874 -0.4064)
			(stroke
				(width 0.1524)
				(type default)
			)
			(layer "B.SilkS")
		)
		(fp_line
			(start -0.67945 -0.3048)
			(end -0.67945 0.3048)
			(stroke
				(width 0.1)
				(type default)
			)
			(layer "B.Fab")
		)
		(fp_line
			(start -0.67945 0.3048)
			(end -0.120396 0.3048)
			(stroke
				(width 0.1)
				(type default)
			)
			(layer "B.Fab")
		)
		(fp_line
			(start -0.12065 -0.3048)
			(end -0.67945 -0.3048)
			(stroke
				(width 0.1)
				(type default)
			)
			(layer "B.Fab")
		)
		(fp_line
			(start -0.12065 -0.2794)
			(end -0.12065 -0.3048)
			(stroke
				(width 0.1)
				(type default)
			)
			(layer "B.Fab")
		)
		(fp_line
			(start -0.120396 0.2794)
			(end 0.12065 0.2794)
			(stroke
				(width 0.1)
				(type default)
			)
			(layer "B.Fab")
		)
		(fp_line
			(start -0.120396 0.3048)
			(end -0.120396 0.2794)
			(stroke
				(width 0.1)
				(type default)
			)
			(layer "B.Fab")
		)
		(fp_line
			(start 0.12065 -0.305054)
			(end 0.12065 -0.2794)
			(stroke
				(width 0.1)
				(type default)
			)
			(layer "B.Fab")
		)
		(fp_line
			(start 0.12065 -0.2794)
			(end -0.12065 -0.2794)
			(stroke
				(width 0.1)
				(type default)
			)
			(layer "B.Fab")
		)
		(fp_line
			(start 0.12065 0.2794)
			(end 0.12065 0.3048)
			(stroke
				(width 0.1)
				(type default)
			)
			(layer "B.Fab")
		)
		(fp_line
			(start 0.12065 0.3048)
			(end 0.67945 0.3048)
			(stroke
				(width 0.1)
				(type default)
			)
			(layer "B.Fab")
		)
		(fp_line
			(start 0.67945 -0.305054)
			(end 0.12065 -0.305054)
			(stroke
				(width 0.1)
				(type default)
			)
			(layer "B.Fab")
		)
		(fp_line
			(start 0.67945 0.3048)
			(end 0.67945 -0.305054)
			(stroke
				(width 0.1)
				(type default)
			)
			(layer "B.Fab")
		)
		(pad "1" smd circle
			(at 0.40005 0 180)
			(size 0 0)
			(layers "B.Cu" "B.Mask" "B.Paste")
			(net "XTAL_CPU0_X48M_X1")
		)
		(pad "2" smd circle
			(at -0.40005 0 180)
			(size 0 0)
			(layers "B.Cu" "B.Mask" "B.Paste")
			(net "GND")
		)
	)
	(footprint ""
		(layer "B.Cu")
		(at 239.903 -216.027)
		(property "Reference" "R365"
			(at 0 0 0)
			(layer "B.SilkS")
			(hide yes)
			(effects
				(font
					(size 1.27 1.27)
				)
				(justify mirror)
			)
		)
		(property "Value" ""
			(at 0 0 0)
			(layer "B.Fab")
			(effects
				(font
					(size 1.27 1.27)
				)
				(justify mirror)
			)
		)
		(duplicate_pad_numbers_are_jumpers no)
		(fp_line
			(start -0.7874 -0.4064)
			(end -0.7874 0.4064)
			(stroke
				(width 0.1524)
				(type default)
			)
			(layer "B.SilkS")
		)
		(fp_line
			(start -0.7874 0.4064)
			(end 0.7874 0.4064)
			(stroke
				(width 0.1524)
				(type default)
			)
			(layer "B.SilkS")
		)
		(fp_line
			(start 0.7874 -0.4064)
			(end -0.7874 -0.4064)
			(stroke
				(width 0.1524)
				(type default)
			)
			(layer "B.SilkS")
		)
		(fp_line
			(start 0.7874 0.4064)
			(end 0.7874 -0.4064)
			(stroke
				(width 0.1524)
				(type default)
			)
			(layer "B.SilkS")
		)
		(fp_line
			(start -0.67945 -0.3048)
			(end -0.67945 0.3048)
			(stroke
				(width 0.1)
				(type default)
			)
			(layer "B.Fab")
		)
		(fp_line
			(start -0.67945 0.3048)
			(end -0.120396 0.3048)
			(stroke
				(width 0.1)
				(type default)
			)
			(layer "B.Fab")
		)
		(fp_line
			(start -0.12065 -0.3048)
			(end -0.67945 -0.3048)
			(stroke
				(width 0.1)
				(type default)
			)
			(layer "B.Fab")
		)
		(fp_line
			(start -0.12065 -0.2794)
			(end -0.12065 -0.3048)
			(stroke
				(width 0.1)
				(type default)
			)
			(layer "B.Fab")
		)
		(fp_line
			(start -0.120396 0.2794)
			(end 0.12065 0.2794)
			(stroke
				(width 0.1)
				(type default)
			)
			(layer "B.Fab")
		)
		(fp_line
			(start -0.120396 0.3048)
			(end -0.120396 0.2794)
			(stroke
				(width 0.1)
				(type default)
			)
			(layer "B.Fab")
		)
		(fp_line
			(start 0.12065 -0.305054)
			(end 0.12065 -0.2794)
			(stroke
				(width 0.1)
				(type default)
			)
			(layer "B.Fab")
		)
		(fp_line
			(start 0.12065 -0.2794)
			(end -0.12065 -0.2794)
			(stroke
				(width 0.1)
				(type default)
			)
			(layer "B.Fab")
		)
		(fp_line
			(start 0.12065 0.2794)
			(end 0.12065 0.3048)
			(stroke
				(width 0.1)
				(type default)
			)
			(layer "B.Fab")
		)
		(fp_line
			(start 0.12065 0.3048)
			(end 0.67945 0.3048)
			(stroke
				(width 0.1)
				(type default)
			)
			(layer "B.Fab")
		)
		(fp_line
			(start 0.67945 -0.305054)
			(end 0.12065 -0.305054)
			(stroke
				(width 0.1)
				(type default)
			)
			(layer "B.Fab")
		)
		(fp_line
			(start 0.67945 0.3048)
			(end 0.67945 -0.305054)
			(stroke
				(width 0.1)
				(type default)
			)
			(layer "B.Fab")
		)
		(pad "1" smd circle
			(at 0.40005 0 180)
			(size 0 0)
			(layers "B.Cu" "B.Mask" "B.Paste")
			(net "P3V3")
		)
		(pad "2" smd circle
			(at -0.40005 0 180)
			(size 0 0)
			(layers "B.Cu" "B.Mask" "B.Paste")
			(net "SMB_CPU0_CPU1_APML_BUF1_SDA_R2")
		)
	)
	(footprint ""
		(layer "B.Cu")
		(at 368.199924 -396.991078 90)
		(property "Reference" "C1053"
			(at 0 0 90)
			(layer "B.SilkS")
			(hide yes)
			(effects
				(font
					(size 1.27 1.27)
				)
				(justify mirror)
			)
		)
		(property "Value" ""
			(at 0 0 90)
			(layer "B.Fab")
			(effects
				(font
					(size 1.27 1.27)
				)
				(justify mirror)
			)
		)
		(duplicate_pad_numbers_are_jumpers no)
		(fp_line
			(start 0.299974 -0.150114)
			(end -0.299974 -0.150114)
			(stroke
				(width 0.1)
				(type default)
			)
			(layer "B.Fab")
		)
		(fp_line
			(start -0.299974 -0.150114)
			(end -0.299974 0.150114)
			(stroke
				(width 0.1)
				(type default)
			)
			(layer "B.Fab")
		)
		(fp_line
			(start 0.299974 0.150114)
			(end 0.299974 -0.150114)
			(stroke
				(width 0.1)
				(type default)
			)
			(layer "B.Fab")
		)
		(fp_line
			(start -0.299974 0.150114)
			(end 0.299974 0.150114)
			(stroke
				(width 0.1)
				(type default)
			)
			(layer "B.Fab")
		)
		(pad "1" smd rect
			(at 0.2667 0 270)
			(size 0.3048 0.381)
			(layers "B.Cu" "B.Mask" "B.Paste")
			(net "P0V9_CPU0_RT3_2A")
		)
		(pad "2" smd rect
			(at -0.2667 0 270)
			(size 0.3048 0.381)
			(layers "B.Cu" "B.Mask" "B.Paste")
			(net "GND")
		)
	)
)
